(kicad_pcb
	(version 20260206)
	(generator "pcbnew")
	(generator_version "10.0")
	(general
		(thickness 1.6)
		(legacy_teardrops no)
	)
	(paper "A4")
	(title_block
		(title "Bryce Canyon_SCC_16316-1_OCP.brd")
		(comment 1 "Bryce Canyon / footprint 64 of 1561 (U1), pads 583-698 of 1020")
	)
	(layers
		(0 "F.Cu" signal "TOP")
		(4 "In1.Cu" signal "L2GND")
		(6 "In2.Cu" signal "L3")
		(8 "In3.Cu" signal "L4VCC")
		(10 "In4.Cu" signal "L5VCC")
		(12 "In5.Cu" signal "L6")
		(14 "In6.Cu" signal "L7GND")
		(2 "B.Cu" signal "BOTTOM")
		(9 "F.Adhes" user "F.Adhesive")
		(11 "B.Adhes" user "B.Adhesive")
		(13 "F.Paste" user "Package Geometry/Pastemask Top")
		(15 "B.Paste" user "Package Geometry/Pastemask Bottom")
		(5 "F.SilkS" user "Ref Des/Silkscreen Top")
		(7 "B.SilkS" user "Ref Des/Silkscreen Bottom")
		(1 "F.Mask" user "Board Geometry/Soldermask Top")
		(3 "B.Mask" user "Board Geometry/Soldermask Bottom")
		(17 "Dwgs.User" user "User.Drawings")
		(19 "Cmts.User" user "User.Comments")
		(21 "Eco1.User" user "User.Eco1")
		(23 "Eco2.User" user "User.Eco2")
		(25 "Edge.Cuts" user "Board Geometry/Outline")
		(27 "Margin" user)
		(31 "F.CrtYd" user "Package Geometry/Place Bound Top")
		(29 "B.CrtYd" user "Package Geometry/Place Bound Bottom")
		(35 "F.Fab" user "Ref Des/Assembly Top")
		(33 "B.Fab" user "Ref Des/Assembly Bottom")
	)
	(footprint ""
		(layer "F.Cu")
		(at 115.000024 -67.00012)
		(property "Reference" "U1"
			(at 0 0 0)
			(layer "F.SilkS")
			(hide yes)
			(effects
				(font
					(size 1.27 1.27)
				)
			)
		)
		(property "Value" "LSISAS3X48-GP"
			(at -24.358092 -5.0292 0)
			(unlocked yes)
			(layer "F.Fab")
			(hide yes)
			(effects
				(font
					(size 1.016 1.016)
					(thickness 0.1524)
				)
			)
		)
		(property "Device Type" "BGA1020C33H83"
			(at -24.358092 -6.5532 0)
			(unlocked yes)
			(layer "F.Fab")
			(hide yes)
			(effects
				(font
					(size 1.016 1.016)
					(thickness 0.1524)
				)
			)
		)
		(duplicate_pad_numbers_are_jumpers no)
		(pad "G11" smd circle
			(at -5.500116 -9.500108)
			(size 0.4572 0.4572)
			(layers "F.Cu" "F.Mask" "F.Paste")
			(net "JTAG_EXP_TDI")
		)
		(pad "G12" smd circle
			(at -4.500118 -9.500108)
			(size 0.4572 0.4572)
			(layers "F.Cu" "F.Mask" "F.Paste")
			(net "EXP_RESET_N")
		)
		(pad "G13" smd circle
			(at -3.50012 -9.500108)
			(size 0.4572 0.4572)
			(layers "F.Cu" "F.Mask" "F.Paste")
			(net "XM_GP_CS_2#_TP")
		)
		(pad "G14" smd circle
			(at -2.500122 -9.500108)
			(size 0.4572 0.4572)
			(layers "F.Cu" "F.Mask" "F.Paste")
			(net "XM_DATA12")
		)
		(pad "G15" smd circle
			(at -1.500124 -9.500108)
			(size 0.4572 0.4572)
			(layers "F.Cu" "F.Mask" "F.Paste")
			(net "GND")
		)
		(pad "G16" smd circle
			(at -0.500126 -9.500108)
			(size 0.4572 0.4572)
			(layers "F.Cu" "F.Mask" "F.Paste")
			(net "EXP_XM_ADDR_20")
		)
		(pad "G17" smd circle
			(at 0.500126 -9.500108)
			(size 0.4572 0.4572)
			(layers "F.Cu" "F.Mask" "F.Paste")
			(net "GND")
		)
		(pad "G18" smd circle
			(at 1.500124 -9.500108)
			(size 0.4572 0.4572)
			(layers "F.Cu" "F.Mask" "F.Paste")
			(net "BMC_LOC_HEARTBEAT_LS")
		)
		(pad "G19" smd circle
			(at 2.500122 -9.500108)
			(size 0.4572 0.4572)
			(layers "F.Cu" "F.Mask" "F.Paste")
			(net "GND")
		)
		(pad "G20" smd circle
			(at 3.50012 -9.500108)
			(size 0.4572 0.4572)
			(layers "F.Cu" "F.Mask" "F.Paste")
			(net "EXP_GPIO1")
		)
		(pad "G21" smd circle
			(at 4.500118 -9.500108)
			(size 0.4572 0.4572)
			(layers "F.Cu" "F.Mask" "F.Paste")
			(net "GND")
		)
		(pad "G22" smd circle
			(at 5.500116 -9.500108)
			(size 0.4572 0.4572)
			(layers "F.Cu" "F.Mask" "F.Paste")
			(net "Net_1202")
		)
		(pad "G23" smd circle
			(at 6.500114 -9.500108)
			(size 0.4572 0.4572)
			(layers "F.Cu" "F.Mask" "F.Paste")
			(net "GND")
		)
		(pad "G24" smd circle
			(at 7.500112 -9.500108)
			(size 0.4572 0.4572)
			(layers "F.Cu" "F.Mask" "F.Paste")
			(net "ICE_TDI")
		)
		(pad "G25" smd circle
			(at 8.50011 -9.500108)
			(size 0.4572 0.4572)
			(layers "F.Cu" "F.Mask" "F.Paste")
			(net "I2C_DPB_SDA3_LS")
		)
		(pad "G26" smd circle
			(at 9.500108 -9.500108)
			(size 0.4572 0.4572)
			(layers "F.Cu" "F.Mask" "F.Paste")
			(net "GND")
		)
		(pad "G27" smd circle
			(at 10.500106 -9.500108)
			(size 0.4572 0.4572)
			(layers "F.Cu" "F.Mask" "F.Paste")
			(net "PHY_CONN_TO_EXP_C_11_DN")
		)
		(pad "G28" smd circle
			(at 11.500104 -9.500108)
			(size 0.4572 0.4572)
			(layers "F.Cu" "F.Mask" "F.Paste")
			(net "PHY_CONN_TO_EXP_C_11_DP")
		)
		(pad "G29" smd circle
			(at 12.500102 -9.500108)
			(size 0.4572 0.4572)
			(layers "F.Cu" "F.Mask" "F.Paste")
			(net "GND")
		)
		(pad "G30" smd circle
			(at 13.5001 -9.500108)
			(size 0.4572 0.4572)
			(layers "F.Cu" "F.Mask" "F.Paste")
			(net "GB_VDDA")
		)
		(pad "G31" smd circle
			(at 14.500098 -9.500108)
			(size 0.4572 0.4572)
			(layers "F.Cu" "F.Mask" "F.Paste")
			(net "PHY_EXP_TO_CONN_C_11_DN")
		)
		(pad "G32" smd circle
			(at 15.500096 -9.500108)
			(size 0.4572 0.4572)
			(layers "F.Cu" "F.Mask" "F.Paste")
			(net "PHY_EXP_TO_CONN_C_11_DP")
		)
		(pad "H1" smd circle
			(at -15.500096 -8.50011)
			(size 0.4572 0.4572)
			(layers "F.Cu" "F.Mask" "F.Paste")
			(net "Net_1282")
		)
		(pad "H2" smd circle
			(at -14.500098 -8.50011)
			(size 0.4572 0.4572)
			(layers "F.Cu" "F.Mask" "F.Paste")
			(net "VDDIO_DDR")
		)
		(pad "H3" smd circle
			(at -13.5001 -8.50011)
			(size 0.4572 0.4572)
			(layers "F.Cu" "F.Mask" "F.Paste")
			(net "Net_1281")
		)
		(pad "H4" smd circle
			(at -12.500102 -8.50011)
			(size 0.4572 0.4572)
			(layers "F.Cu" "F.Mask" "F.Paste")
			(net "VDDIO_DDR")
		)
		(pad "H5" smd circle
			(at -11.500104 -8.50011)
			(size 0.4572 0.4572)
			(layers "F.Cu" "F.Mask" "F.Paste")
			(net "Net_1280")
		)
		(pad "H6" smd circle
			(at -10.500106 -8.50011)
			(size 0.4572 0.4572)
			(layers "F.Cu" "F.Mask" "F.Paste")
			(net "VDDIO_DDR")
		)
		(pad "H7" smd circle
			(at -9.500108 -8.50011)
			(size 0.4572 0.4572)
			(layers "F.Cu" "F.Mask" "F.Paste")
			(net "Net_1237")
		)
		(pad "H8" smd circle
			(at -8.50011 -8.50011)
			(size 0.4572 0.4572)
			(layers "F.Cu" "F.Mask" "F.Paste")
			(net "GND")
		)
		(pad "H9" smd circle
			(at -7.500112 -8.50011)
			(size 0.4572 0.4572)
			(layers "F.Cu" "F.Mask" "F.Paste")
			(net "LED11")
		)
		(pad "H10" smd circle
			(at -6.500114 -8.50011)
			(size 0.4572 0.4572)
			(layers "F.Cu" "F.Mask" "F.Paste")
			(net "SXP_ACTIVE_0")
		)
		(pad "H11" smd circle
			(at -5.500116 -8.50011)
			(size 0.4572 0.4572)
			(layers "F.Cu" "F.Mask" "F.Paste")
			(net "JTAG_EXP_TCK")
		)
		(pad "H12" smd circle
			(at -4.500118 -8.50011)
			(size 0.4572 0.4572)
			(layers "F.Cu" "F.Mask" "F.Paste")
			(net "EXP_CLK_SEL1")
		)
		(pad "H13" smd circle
			(at -3.50012 -8.50011)
			(size 0.4572 0.4572)
			(layers "F.Cu" "F.Mask" "F.Paste")
			(net "EXP_XM_CS_N_0")
		)
		(pad "H14" smd circle
			(at -2.500122 -8.50011)
			(size 0.4572 0.4572)
			(layers "F.Cu" "F.Mask" "F.Paste")
			(net "XM_DATA11")
		)
		(pad "H15" smd circle
			(at -1.500124 -8.50011)
			(size 0.4572 0.4572)
			(layers "F.Cu" "F.Mask" "F.Paste")
			(net "P1V8_E")
		)
		(pad "H16" smd circle
			(at -0.500126 -8.50011)
			(size 0.4572 0.4572)
			(layers "F.Cu" "F.Mask" "F.Paste")
			(net "EXP_XM_ADDR_21")
		)
		(pad "H17" smd circle
			(at 0.500126 -8.50011)
			(size 0.4572 0.4572)
			(layers "F.Cu" "F.Mask" "F.Paste")
			(net "P1V8_E")
		)
		(pad "H18" smd circle
			(at 1.500124 -8.50011)
			(size 0.4572 0.4572)
			(layers "F.Cu" "F.Mask" "F.Paste")
			(net "COMP_EXP_SPARE_1_R_LS")
		)
		(pad "H19" smd circle
			(at 2.500122 -8.50011)
			(size 0.4572 0.4572)
			(layers "F.Cu" "F.Mask" "F.Paste")
			(net "P1V8_E")
		)
		(pad "H20" smd circle
			(at 3.50012 -8.50011)
			(size 0.4572 0.4572)
			(layers "F.Cu" "F.Mask" "F.Paste")
			(net "Net_1224")
		)
		(pad "H21" smd circle
			(at 4.500118 -8.50011)
			(size 0.4572 0.4572)
			(layers "F.Cu" "F.Mask" "F.Paste")
			(net "P1V8_E")
		)
		(pad "H22" smd circle
			(at 5.500116 -8.50011)
			(size 0.4572 0.4572)
			(layers "F.Cu" "F.Mask" "F.Paste")
			(net "Net_1218")
		)
		(pad "H23" smd circle
			(at 6.500114 -8.50011)
			(size 0.4572 0.4572)
			(layers "F.Cu" "F.Mask" "F.Paste")
			(net "P1V8_E")
		)
		(pad "H24" smd circle
			(at 7.500112 -8.50011)
			(size 0.4572 0.4572)
			(layers "F.Cu" "F.Mask" "F.Paste")
			(net "EXP_SIO_CLK_OUT")
		)
		(pad "H25" smd circle
			(at 8.50011 -8.50011)
			(size 0.4572 0.4572)
			(layers "F.Cu" "F.Mask" "F.Paste")
			(net "P1V8_E")
		)
		(pad "H26" smd circle
			(at 9.500108 -8.50011)
			(size 0.4572 0.4572)
			(layers "F.Cu" "F.Mask" "F.Paste")
			(net "GND")
		)
		(pad "H27" smd circle
			(at 10.500106 -8.50011)
			(size 0.4572 0.4572)
			(layers "F.Cu" "F.Mask" "F.Paste")
			(net "PHY_CONN_TO_EXP_C_10_DN")
		)
		(pad "H28" smd circle
			(at 11.500104 -8.50011)
			(size 0.4572 0.4572)
			(layers "F.Cu" "F.Mask" "F.Paste")
			(net "PHY_CONN_TO_EXP_C_10_DP")
		)
		(pad "H29" smd circle
			(at 12.500102 -8.50011)
			(size 0.4572 0.4572)
			(layers "F.Cu" "F.Mask" "F.Paste")
			(net "GB_VDDA")
		)
		(pad "H30" smd circle
			(at 13.5001 -8.50011)
			(size 0.4572 0.4572)
			(layers "F.Cu" "F.Mask" "F.Paste")
			(net "PHY_EXP_TO_CONN_C_10_DN")
		)
		(pad "H31" smd circle
			(at 14.500098 -8.50011)
			(size 0.4572 0.4572)
			(layers "F.Cu" "F.Mask" "F.Paste")
			(net "PHY_EXP_TO_CONN_C_10_DP")
		)
		(pad "H32" smd circle
			(at 15.500096 -8.50011)
			(size 0.4572 0.4572)
			(layers "F.Cu" "F.Mask" "F.Paste")
			(net "GND")
		)
		(pad "J1" smd circle
			(at -15.500096 -7.500112)
			(size 0.4572 0.4572)
			(layers "F.Cu" "F.Mask" "F.Paste")
			(net "Net_1279")
		)
		(pad "J2" smd circle
			(at -14.500098 -7.500112)
			(size 0.4572 0.4572)
			(layers "F.Cu" "F.Mask" "F.Paste")
			(net "Net_1278")
		)
		(pad "J3" smd circle
			(at -13.5001 -7.500112)
			(size 0.4572 0.4572)
			(layers "F.Cu" "F.Mask" "F.Paste")
			(net "GND")
		)
		(pad "J4" smd circle
			(at -12.500102 -7.500112)
			(size 0.4572 0.4572)
			(layers "F.Cu" "F.Mask" "F.Paste")
			(net "Net_1277")
		)
		(pad "J5" smd circle
			(at -11.500104 -7.500112)
			(size 0.4572 0.4572)
			(layers "F.Cu" "F.Mask" "F.Paste")
			(net "GND")
		)
		(pad "J6" smd circle
			(at -10.500106 -7.500112)
			(size 0.4572 0.4572)
			(layers "F.Cu" "F.Mask" "F.Paste")
			(net "Net_1236")
		)
		(pad "J7" smd circle
			(at -9.500108 -7.500112)
			(size 0.4572 0.4572)
			(layers "F.Cu" "F.Mask" "F.Paste")
			(net "Net_1235")
		)
		(pad "J8" smd circle
			(at -8.50011 -7.500112)
			(size 0.4572 0.4572)
			(layers "F.Cu" "F.Mask" "F.Paste")
			(net "Net_1234")
		)
		(pad "J9" smd circle
			(at -7.500112 -7.500112)
			(size 0.4572 0.4572)
			(layers "F.Cu" "F.Mask" "F.Paste")
			(net "GND")
		)
		(pad "J10" smd circle
			(at -6.500114 -7.500112)
			(size 0.4572 0.4572)
			(layers "F.Cu" "F.Mask" "F.Paste")
			(net "LED8")
		)
		(pad "J11" smd circle
			(at -5.500116 -7.500112)
			(size 0.4572 0.4572)
			(layers "F.Cu" "F.Mask" "F.Paste")
			(net "LSI_T_N")
		)
		(pad "J12" smd circle
			(at -4.500118 -7.500112)
			(size 0.4572 0.4572)
			(layers "F.Cu" "F.Mask" "F.Paste")
			(net "EXP_CLK_SEL0")
		)
		(pad "J13" smd circle
			(at -3.50012 -7.500112)
			(size 0.4572 0.4572)
			(layers "F.Cu" "F.Mask" "F.Paste")
			(net "XM_DATA9")
		)
		(pad "J14" smd circle
			(at -2.500122 -7.500112)
			(size 0.4572 0.4572)
			(layers "F.Cu" "F.Mask" "F.Paste")
			(net "XM_DATA0")
		)
		(pad "J15" smd circle
			(at -1.500124 -7.500112)
			(size 0.4572 0.4572)
			(layers "F.Cu" "F.Mask" "F.Paste")
			(net "EXP_XM_ADDR_6")
		)
		(pad "J16" smd circle
			(at -0.500126 -7.500112)
			(size 0.4572 0.4572)
			(layers "F.Cu" "F.Mask" "F.Paste")
			(net "EXP_XM_ADDR_2")
		)
		(pad "J17" smd circle
			(at 0.500126 -7.500112)
			(size 0.4572 0.4572)
			(layers "F.Cu" "F.Mask" "F.Paste")
			(net "Net_135")
		)
		(pad "J18" smd circle
			(at 1.500124 -7.500112)
			(size 0.4572 0.4572)
			(layers "F.Cu" "F.Mask" "F.Paste")
			(net "SCC_TYPE_1_LS")
		)
		(pad "J19" smd circle
			(at 2.500122 -7.500112)
			(size 0.4572 0.4572)
			(layers "F.Cu" "F.Mask" "F.Paste")
			(net "Net_1223")
		)
		(pad "J20" smd circle
			(at 3.50012 -7.500112)
			(size 0.4572 0.4572)
			(layers "F.Cu" "F.Mask" "F.Paste")
			(net "Net_1222")
		)
		(pad "J21" smd circle
			(at 4.500118 -7.500112)
			(size 0.4572 0.4572)
			(layers "F.Cu" "F.Mask" "F.Paste")
			(net "Net_1217")
		)
		(pad "J22" smd circle
			(at 5.500116 -7.500112)
			(size 0.4572 0.4572)
			(layers "F.Cu" "F.Mask" "F.Paste")
			(net "Net_1216")
		)
		(pad "J23" smd circle
			(at 6.500114 -7.500112)
			(size 0.4572 0.4572)
			(layers "F.Cu" "F.Mask" "F.Paste")
			(net "EXP_SIO_CLK_IN")
		)
		(pad "J24" smd circle
			(at 7.500112 -7.500112)
			(size 0.4572 0.4572)
			(layers "F.Cu" "F.Mask" "F.Paste")
			(net "I2C_DRIVE_PWR_SDA4_LS")
		)
		(pad "J25" smd circle
			(at 8.50011 -7.500112)
			(size 0.4572 0.4572)
			(layers "F.Cu" "F.Mask" "F.Paste")
			(net "I2C_SCC_SDA2_LS")
		)
		(pad "J26" smd circle
			(at 9.500108 -7.500112)
			(size 0.4572 0.4572)
			(layers "F.Cu" "F.Mask" "F.Paste")
			(net "GND")
		)
		(pad "J27" smd circle
			(at 10.500106 -7.500112)
			(size 0.4572 0.4572)
			(layers "F.Cu" "F.Mask" "F.Paste")
			(net "PHY_CONN_TO_EXP_C_9_DN")
		)
		(pad "J28" smd circle
			(at 11.500104 -7.500112)
			(size 0.4572 0.4572)
			(layers "F.Cu" "F.Mask" "F.Paste")
			(net "PHY_CONN_TO_EXP_C_9_DP")
		)
		(pad "J29" smd circle
			(at 12.500102 -7.500112)
			(size 0.4572 0.4572)
			(layers "F.Cu" "F.Mask" "F.Paste")
			(net "GND")
		)
		(pad "J30" smd circle
			(at 13.5001 -7.500112)
			(size 0.4572 0.4572)
			(layers "F.Cu" "F.Mask" "F.Paste")
			(net "GB_VDDA")
		)
		(pad "J31" smd circle
			(at 14.500098 -7.500112)
			(size 0.4572 0.4572)
			(layers "F.Cu" "F.Mask" "F.Paste")
			(net "PHY_EXP_TO_CONN_C_9_DN")
		)
		(pad "J32" smd circle
			(at 15.500096 -7.500112)
			(size 0.4572 0.4572)
			(layers "F.Cu" "F.Mask" "F.Paste")
			(net "PHY_EXP_TO_CONN_C_9_DP")
		)
		(pad "K1" smd circle
			(at -15.500096 -6.500114)
			(size 0.4572 0.4572)
			(layers "F.Cu" "F.Mask" "F.Paste")
			(net "Net_1276")
		)
		(pad "K2" smd circle
			(at -14.500098 -6.500114)
			(size 0.4572 0.4572)
			(layers "F.Cu" "F.Mask" "F.Paste")
			(net "VDDIO_DDR")
		)
		(pad "K3" smd circle
			(at -13.5001 -6.500114)
			(size 0.4572 0.4572)
			(layers "F.Cu" "F.Mask" "F.Paste")
			(net "Net_1275")
		)
		(pad "K4" smd circle
			(at -12.500102 -6.500114)
			(size 0.4572 0.4572)
			(layers "F.Cu" "F.Mask" "F.Paste")
			(net "VDDIO_DDR")
		)
		(pad "K5" smd circle
			(at -11.500104 -6.500114)
			(size 0.4572 0.4572)
			(layers "F.Cu" "F.Mask" "F.Paste")
			(net "Net_1274")
		)
		(pad "K6" smd circle
			(at -10.500106 -6.500114)
			(size 0.4572 0.4572)
			(layers "F.Cu" "F.Mask" "F.Paste")
			(net "VDDIO_DDR")
		)
		(pad "K7" smd circle
			(at -9.500108 -6.500114)
			(size 0.4572 0.4572)
			(layers "F.Cu" "F.Mask" "F.Paste")
			(net "Net_1233")
		)
		(pad "K8" smd circle
			(at -8.50011 -6.500114)
			(size 0.4572 0.4572)
			(layers "F.Cu" "F.Mask" "F.Paste")
			(net "Net_1232")
		)
		(pad "K9" smd circle
			(at -7.500112 -6.500114)
			(size 0.4572 0.4572)
			(layers "F.Cu" "F.Mask" "F.Paste")
			(net "GND")
		)
		(pad "K10" smd circle
			(at -6.500114 -6.500114)
			(size 0.4572 0.4572)
			(layers "F.Cu" "F.Mask" "F.Paste")
			(net "EXP_ADC_IN1")
		)
		(pad "K11" smd circle
			(at -5.500116 -6.500114)
			(size 0.4572 0.4572)
			(layers "F.Cu" "F.Mask" "F.Paste")
			(net "SXP_ACTIVE_1")
		)
		(pad "K12" smd circle
			(at -4.500118 -6.500114)
			(size 0.4572 0.4572)
			(layers "F.Cu" "F.Mask" "F.Paste")
			(net "EXP_CPU_MODE_0")
		)
		(pad "K13" smd circle
			(at -3.50012 -6.500114)
			(size 0.4572 0.4572)
			(layers "F.Cu" "F.Mask" "F.Paste")
			(net "EXP_XM_NOR_CS_N")
		)
		(pad "K14" smd circle
			(at -2.500122 -6.500114)
			(size 0.4572 0.4572)
			(layers "F.Cu" "F.Mask" "F.Paste")
			(net "XM_DATA13")
		)
		(pad "K15" smd circle
			(at -1.500124 -6.500114)
			(size 0.4572 0.4572)
			(layers "F.Cu" "F.Mask" "F.Paste")
			(net "EXP_XM_ADDR_24")
		)
		(pad "K16" smd circle
			(at -0.500126 -6.500114)
			(size 0.4572 0.4572)
			(layers "F.Cu" "F.Mask" "F.Paste")
			(net "EXP_XM_ADDR_15")
		)
		(pad "K17" smd circle
			(at 0.500126 -6.500114)
			(size 0.4572 0.4572)
			(layers "F.Cu" "F.Mask" "F.Paste")
			(net "EXP_GPIO14")
		)
		(pad "K18" smd circle
			(at 1.500124 -6.500114)
			(size 0.4572 0.4572)
			(layers "F.Cu" "F.Mask" "F.Paste")
			(net "DRIVE_INSERT_ALERT_LS_N")
		)
		(pad "K19" smd circle
			(at 2.500122 -6.500114)
			(size 0.4572 0.4572)
			(layers "F.Cu" "F.Mask" "F.Paste")
			(net "Net_1221")
		)
		(pad "K20" smd circle
			(at 3.50012 -6.500114)
			(size 0.4572 0.4572)
			(layers "F.Cu" "F.Mask" "F.Paste")
			(net "Net_1220")
		)
		(pad "K21" smd circle
			(at 4.500118 -6.500114)
			(size 0.4572 0.4572)
			(layers "F.Cu" "F.Mask" "F.Paste")
			(net "ICE_TCK")
		)
		(pad "K22" smd circle
			(at 5.500116 -6.500114)
			(size 0.4572 0.4572)
			(layers "F.Cu" "F.Mask" "F.Paste")
			(net "EXP_SIO_LOAD_OUT")
		)
		(pad "K23" smd circle
			(at 6.500114 -6.500114)
			(size 0.4572 0.4572)
			(layers "F.Cu" "F.Mask" "F.Paste")
			(net "I2C_CLIP_SCL7_LS")
		)
		(pad "K24" smd circle
			(at 7.500112 -6.500114)
			(size 0.4572 0.4572)
			(layers "F.Cu" "F.Mask" "F.Paste")
			(net "I2C_DPB_SCL3_LS")
		)
		(pad "K25" smd circle
			(at 8.50011 -6.500114)
			(size 0.4572 0.4572)
			(layers "F.Cu" "F.Mask" "F.Paste")
			(net "GND")
		)
		(pad "K26" smd circle
			(at 9.500108 -6.500114)
			(size 0.4572 0.4572)
			(layers "F.Cu" "F.Mask" "F.Paste")
			(net "GND")
		)
		(pad "K27" smd circle
			(at 10.500106 -6.500114)
			(size 0.4572 0.4572)
			(layers "F.Cu" "F.Mask" "F.Paste")
			(net "PHY_CONN_TO_EXP_C_8_DN")
		)
		(pad "K28" smd circle
			(at 11.500104 -6.500114)
			(size 0.4572 0.4572)
			(layers "F.Cu" "F.Mask" "F.Paste")
			(net "PHY_CONN_TO_EXP_C_8_DP")
		)
		(pad "K29" smd circle
			(at 12.500102 -6.500114)
			(size 0.4572 0.4572)
			(layers "F.Cu" "F.Mask" "F.Paste")
			(net "GB_VDDA")
		)
		(pad "K30" smd circle
			(at 13.5001 -6.500114)
			(size 0.4572 0.4572)
			(layers "F.Cu" "F.Mask" "F.Paste")
			(net "PHY_EXP_TO_CONN_C_8_DN")
		)
	)
)
